# T6G (Grand Teton) — schematic netlist excerpt (pin names and nets, part order shuffled) for the footprints in the layout excerpt that follows; sources: Cadence DE-HDL packaged netlist, KiCad conversion of 04192023_DAF0TMB3IC0_F0TG_MB_C_brd_V02_OCP.brd

C6688  Q_CAP_DIFFBUS  DIFF BUS_0.22UF 6.3V 20% X6S  pkg C0201  page 330 : \1\ = P5E_CPU1_P1_TX_BUF_C_DN<13> ; \2\ = P5E_CPU1_P1_TX_BUF_DN<13>
C6738  Q_CAP_DIFFBUS  DIFF BUS_0.22UF 6.3V 20% X6S  pkg C0201  page 352 : \1\ = P5E_CPU1_P3_TX_BUF_C_DN<6> ; \2\ = P5E_CPU1_P3_TX_BUF_DN<6>
R6780  Q_RES  33.2 1% CHIP  pkg 0201LF  page 184 : A = SMB_MUX_RT_SCL ; B = SMB_MUX_RT_R1_SCL
C151  Q_CAP  10UF 25V 10% X6S  pkg C0805  page 90 : A = P12V_MEM_CPU0 ; B = GND
PC409_4  Q_CAP  22UF 16V 20% X6S  pkg C0805  page 219 : A = SW_P12V_AUX_PVDDCR_CPU1_P1_FLT ; B = GND

(kicad_pcb
	(version 20260206)
	(generator "pcbnew")
	(generator_version "10.0")
	(general
		(thickness 1.6)
		(legacy_teardrops no)
	)
	(paper "A4")
	(title_block
		(title "04192023_DAF0TMB3IC0_F0TG_MB_C_brd_V02_OCP.brd")
		(comment 1 "Grand Teton / footprints 5912-5916 of 8354")
	)
	(layers
		(0 "F.Cu" signal "TOP")
		(4 "In1.Cu" signal "GND")
		(6 "In2.Cu" signal "IN1")
		(8 "In3.Cu" signal "GND1")
		(10 "In4.Cu" signal "IN2")
		(12 "In5.Cu" signal "GND2")
		(14 "In6.Cu" signal "IN3")
		(16 "In7.Cu" signal "GND3")
		(18 "In8.Cu" signal "VCC")
		(20 "In9.Cu" signal "VCC1")
		(22 "In10.Cu" signal "GND4")
		(24 "In11.Cu" signal "IN4")
		(26 "In12.Cu" signal "GND5")
		(28 "In13.Cu" signal "IN5")
		(30 "In14.Cu" signal "GND6")
		(32 "In15.Cu" signal "IN6")
		(34 "In16.Cu" signal "GND7")
		(2 "B.Cu" signal "BOTTOM")
		(9 "F.Adhes" user "F.Adhesive")
		(11 "B.Adhes" user "B.Adhesive")
		(13 "F.Paste" user "Package Geometry/Pastemask Top")
		(15 "B.Paste" user "Package Geometry/Pastemask Bottom")
		(5 "F.SilkS" user "Ref Des/Silkscreen Top")
		(7 "B.SilkS" user "Ref Des/Silkscreen Bottom")
		(1 "F.Mask" user "Board Geometry/Soldermask Top")
		(3 "B.Mask" user "Board Geometry/Soldermask Bottom")
		(17 "Dwgs.User" user "User.Drawings")
		(19 "Cmts.User" user "User.Comments")
		(21 "Eco1.User" user "User.Eco1")
		(23 "Eco2.User" user "User.Eco2")
		(25 "Edge.Cuts" user "Board Geometry/Outline")
		(27 "Margin" user)
		(31 "F.CrtYd" user "Package Geometry/Place Bound Top")
		(29 "B.CrtYd" user "Package Geometry/Place Bound Bottom")
		(35 "F.Fab" user "Ref Des/Assembly Top")
		(33 "B.Fab" user "Ref Des/Assembly Bottom")
	)
	(footprint ""
		(layer "B.Cu")
		(at 62.996318 -346.788994 90)
		(property "Reference" "PC409_4"
			(at 0 0 90)
			(layer "B.SilkS")
			(hide yes)
			(effects
				(font
					(size 1.27 1.27)
				)
				(justify mirror)
			)
		)
		(property "Value" ""
			(at 0 0 90)
			(layer "B.Fab")
			(effects
				(font
					(size 1.27 1.27)
				)
				(justify mirror)
			)
		)
		(duplicate_pad_numbers_are_jumpers no)
		(fp_line
			(start 1.524 -0.762)
			(end -1.524 -0.762)
			(stroke
				(width 0.1524)
				(type default)
			)
			(layer "B.SilkS")
		)
		(fp_line
			(start -1.524 -0.762)
			(end -1.524 0.762)
			(stroke
				(width 0.1524)
				(type default)
			)
			(layer "B.SilkS")
		)
		(fp_line
			(start 1.524 0.762)
			(end 1.524 -0.762)
			(stroke
				(width 0.1524)
				(type default)
			)
			(layer "B.SilkS")
		)
		(fp_line
			(start -1.524 0.762)
			(end 1.524 0.762)
			(stroke
				(width 0.1524)
				(type default)
			)
			(layer "B.SilkS")
		)
		(fp_line
			(start 1.1049 -0.724916)
			(end 1.1049 0.724916)
			(stroke
				(width 0.1)
				(type default)
			)
			(layer "B.Fab")
		)
		(fp_line
			(start -1.1049 -0.724916)
			(end 1.1049 -0.724916)
			(stroke
				(width 0.1)
				(type default)
			)
			(layer "B.Fab")
		)
		(fp_line
			(start 1.1049 0.724916)
			(end -1.1049 0.724916)
			(stroke
				(width 0.1)
				(type default)
			)
			(layer "B.Fab")
		)
		(fp_line
			(start -1.1049 0.724916)
			(end -1.1049 -0.724916)
			(stroke
				(width 0.1)
				(type default)
			)
			(layer "B.Fab")
		)
		(pad "1" smd rect
			(at 0.889 0 90)
			(size 1.016 1.27)
			(layers "B.Cu" "B.Mask" "B.Paste")
			(net "SW_P12V_AUX_PVDDCR_CPU1_P1_FLT")
		)
		(pad "2" smd rect
			(at -0.889 0 90)
			(size 1.016 1.27)
			(layers "B.Cu" "B.Mask" "B.Paste")
			(net "GND")
		)
	)
	(footprint ""
		(layer "B.Cu")
		(at 134.779766 -408.517344 90)
		(property "Reference" "C6738"
			(at 0 0 90)
			(layer "B.SilkS")
			(hide yes)
			(effects
				(font
					(size 1.27 1.27)
				)
				(justify mirror)
			)
		)
		(property "Value" ""
			(at 0 0 90)
			(layer "B.Fab")
			(effects
				(font
					(size 1.27 1.27)
				)
				(justify mirror)
			)
		)
		(duplicate_pad_numbers_are_jumpers no)
		(fp_line
			(start 0.299974 -0.150114)
			(end -0.299974 -0.150114)
			(stroke
				(width 0.1)
				(type default)
			)
			(layer "B.Fab")
		)
		(fp_line
			(start -0.299974 -0.150114)
			(end -0.299974 0.150114)
			(stroke
				(width 0.1)
				(type default)
			)
			(layer "B.Fab")
		)
		(fp_line
			(start 0.299974 0.150114)
			(end 0.299974 -0.150114)
			(stroke
				(width 0.1)
				(type default)
			)
			(layer "B.Fab")
		)
		(fp_line
			(start -0.299974 0.150114)
			(end 0.299974 0.150114)
			(stroke
				(width 0.1)
				(type default)
			)
			(layer "B.Fab")
		)
		(pad "1" smd rect
			(at 0.2667 0 270)
			(size 0.3048 0.381)
			(layers "B.Cu" "B.Mask" "B.Paste")
			(net "P5E_CPU1_P3_TX_BUF_C_DN<6>")
		)
		(pad "2" smd rect
			(at -0.2667 0 270)
			(size 0.3048 0.381)
			(layers "B.Cu" "B.Mask" "B.Paste")
			(net "P5E_CPU1_P3_TX_BUF_DN<6>")
		)
	)
	(footprint ""
		(layer "B.Cu")
		(at 277.192232 -192.660016)
		(property "Reference" "C151"
			(at 0 0 0)
			(layer "B.SilkS")
			(hide yes)
			(effects
				(font
					(size 1.27 1.27)
				)
				(justify mirror)
			)
		)
		(property "Value" ""
			(at 0 0 0)
			(layer "B.Fab")
			(effects
				(font
					(size 1.27 1.27)
				)
				(justify mirror)
			)
		)
		(duplicate_pad_numbers_are_jumpers no)
		(fp_line
			(start -1.524 -0.762)
			(end -1.524 0.762)
			(stroke
				(width 0.1524)
				(type default)
			)
			(layer "B.SilkS")
		)
		(fp_line
			(start -1.524 0.762)
			(end 1.524 0.762)
			(stroke
				(width 0.1524)
				(type default)
			)
			(layer "B.SilkS")
		)
		(fp_line
			(start 1.524 -0.762)
			(end -1.524 -0.762)
			(stroke
				(width 0.1524)
				(type default)
			)
			(layer "B.SilkS")
		)
		(fp_line
			(start 1.524 0.762)
			(end 1.524 -0.762)
			(stroke
				(width 0.1524)
				(type default)
			)
			(layer "B.SilkS")
		)
		(fp_line
			(start -1.1049 -0.724916)
			(end 1.1049 -0.724916)
			(stroke
				(width 0.1)
				(type default)
			)
			(layer "B.Fab")
		)
		(fp_line
			(start -1.1049 0.724916)
			(end -1.1049 -0.724916)
			(stroke
				(width 0.1)
				(type default)
			)
			(layer "B.Fab")
		)
		(fp_line
			(start 1.1049 -0.724916)
			(end 1.1049 0.724916)
			(stroke
				(width 0.1)
				(type default)
			)
			(layer "B.Fab")
		)
		(fp_line
			(start 1.1049 0.724916)
			(end -1.1049 0.724916)
			(stroke
				(width 0.1)
				(type default)
			)
			(layer "B.Fab")
		)
		(pad "1" smd rect
			(at 0.889 0)
			(size 1.016 1.27)
			(layers "B.Cu" "B.Mask" "B.Paste")
			(net "P12V_MEM_CPU0")
		)
		(pad "2" smd rect
			(at -0.889 0)
			(size 1.016 1.27)
			(layers "B.Cu" "B.Mask" "B.Paste")
			(net "GND")
		)
	)
	(footprint ""
		(layer "B.Cu")
		(at 230.886 -331.724 180)
		(property "Reference" "R6780"
			(at 0 0 0)
			(layer "B.SilkS")
			(hide yes)
			(effects
				(font
					(size 1.27 1.27)
				)
				(justify mirror)
			)
		)
		(property "Value" ""
			(at 0 0 0)
			(layer "B.Fab")
			(effects
				(font
					(size 1.27 1.27)
				)
				(justify mirror)
			)
		)
		(duplicate_pad_numbers_are_jumpers no)
		(fp_line
			(start 0.32512 0.175006)
			(end 0.32512 -0.175006)
			(stroke
				(width 0.1)
				(type default)
			)
			(layer "B.Fab")
		)
		(fp_line
			(start 0.32512 -0.175006)
			(end -0.32512 -0.175006)
			(stroke
				(width 0.1)
				(type default)
			)
			(layer "B.Fab")
		)
		(fp_line
			(start -0.32512 0.175006)
			(end 0.32512 0.175006)
			(stroke
				(width 0.1)
				(type default)
			)
			(layer "B.Fab")
		)
		(fp_line
			(start -0.32512 -0.175006)
			(end -0.32512 0.175006)
			(stroke
				(width 0.1)
				(type default)
			)
			(layer "B.Fab")
		)
		(pad "1" smd rect
			(at 0.2667 0)
			(size 0.3048 0.381)
			(layers "B.Cu" "B.Mask" "B.Paste")
			(net "SMB_MUX_RT_SCL")
		)
		(pad "2" smd rect
			(at -0.2667 0 180)
			(size 0.3048 0.381)
			(layers "B.Cu" "B.Mask" "B.Paste")
			(net "SMB_MUX_RT_R1_SCL")
		)
	)
	(footprint ""
		(layer "B.Cu")
		(at 89.122504 -408.517344 90)
		(property "Reference" "C6688"
			(at 0 0 90)
			(layer "B.SilkS")
			(hide yes)
			(effects
				(font
					(size 1.27 1.27)
				)
				(justify mirror)
			)
		)
		(property "Value" ""
			(at 0 0 90)
			(layer "B.Fab")
			(effects
				(font
					(size 1.27 1.27)
				)
				(justify mirror)
			)
		)
		(duplicate_pad_numbers_are_jumpers no)
		(fp_line
			(start 0.299974 -0.150114)
			(end -0.299974 -0.150114)
			(stroke
				(width 0.1)
				(type default)
			)
			(layer "B.Fab")
		)
		(fp_line
			(start -0.299974 -0.150114)
			(end -0.299974 0.150114)
			(stroke
				(width 0.1)
				(type default)
			)
			(layer "B.Fab")
		)
		(fp_line
			(start 0.299974 0.150114)
			(end 0.299974 -0.150114)
			(stroke
				(width 0.1)
				(type default)
			)
			(layer "B.Fab")
		)
		(fp_line
			(start -0.299974 0.150114)
			(end 0.299974 0.150114)
			(stroke
				(width 0.1)
				(type default)
			)
			(layer "B.Fab")
		)
		(pad "1" smd rect
			(at 0.2667 0 270)
			(size 0.3048 0.381)
			(layers "B.Cu" "B.Mask" "B.Paste")
			(net "P5E_CPU1_P1_TX_BUF_C_DN<13>")
		)
		(pad "2" smd rect
			(at -0.2667 0 270)
			(size 0.3048 0.381)
			(layers "B.Cu" "B.Mask" "B.Paste")
			(net "P5E_CPU1_P1_TX_BUF_DN<13>")
		)
	)
)
